(kicad_pcb
	(version 20260206)
	(generator "pcbnew")
	(generator_version "10.0")
	(general
		(thickness 1.6)
		(legacy_teardrops no)
	)
	(paper "A4")
	(title_block
		(title "Bryce Canyon_F.DPB_16315-1-OCP.brd")
		(comment 1 "Bryce Canyon / footprints 2223-2223 of 2223")
	)
	(layers
		(0 "F.Cu" signal "TOP")
		(4 "In1.Cu" signal "L2GND")
		(6 "In2.Cu" signal "L3")
		(8 "In3.Cu" signal "L4GND")
		(10 "In4.Cu" signal "L5")
		(12 "In5.Cu" signal "L6VCC")
		(14 "In6.Cu" signal "L7VCC")
		(16 "In7.Cu" signal "L8")
		(18 "In8.Cu" signal "L9GND")
		(20 "In9.Cu" signal "L10")
		(22 "In10.Cu" signal "L11GND")
		(2 "B.Cu" signal "BOTTOM")
		(9 "F.Adhes" user "F.Adhesive")
		(11 "B.Adhes" user "B.Adhesive")
		(13 "F.Paste" user "Package Geometry/Pastemask Top")
		(15 "B.Paste" user "Package Geometry/Pastemask Bottom")
		(5 "F.SilkS" user "Ref Des/Silkscreen Top")
		(7 "B.SilkS" user "Ref Des/Silkscreen Bottom")
		(1 "F.Mask" user "Board Geometry/Soldermask Top")
		(3 "B.Mask" user "Board Geometry/Soldermask Bottom")
		(17 "Dwgs.User" user "User.Drawings")
		(19 "Cmts.User" user "User.Comments")
		(21 "Eco1.User" user "User.Eco1")
		(23 "Eco2.User" user "User.Eco2")
		(25 "Edge.Cuts" user "Board Geometry/Outline")
		(27 "Margin" user)
		(31 "F.CrtYd" user "Package Geometry/Place Bound Top")
		(29 "B.CrtYd" user "Package Geometry/Place Bound Bottom")
		(35 "F.Fab" user "Ref Des/Assembly Top")
		(33 "B.Fab" user "Ref Des/Assembly Bottom")
	)
	(footprint ""
		(layer "B.Cu")
		(at 189.905894 -220.688916 -90)
		(property "Reference" "C673"
			(at 0 0 90)
			(layer "B.SilkS")
			(hide yes)
			(effects
				(font
					(size 1.27 1.27)
				)
				(justify mirror)
			)
		)
		(property "Value" "SC100P50V2JN-3GP"
			(at -1.1811 -2.7051 270)
			(unlocked yes)
			(layer "B.Fab")
			(hide yes)
			(effects
				(font
					(size 1.016 1.016)
					(thickness 0.1524)
				)
				(justify mirror)
			)
		)
		(property "Device Type" "C402H22"
			(at -1.1811 -4.2291 270)
			(unlocked yes)
			(layer "B.Fab")
			(hide yes)
			(effects
				(font
					(size 1.016 1.016)
					(thickness 0.1524)
				)
				(justify mirror)
			)
		)
		(duplicate_pad_numbers_are_jumpers no)
		(fp_rect
			(start 0.4318 0.9525)
			(end -0.4318 -0.9525)
			(stroke
				(width 0)
				(type default)
			)
			(fill no)
			(layer "B.CrtYd")
		)
		(fp_rect
			(start 0.4318 0.9525)
			(end -0.4318 -0.9525)
			(stroke
				(width 0)
				(type default)
			)
			(fill no)
			(layer "B.Fab")
		)
		(pad "1" smd custom
			(at 0 -0.4445 90)
			(size 0.1524 0.1524)
			(layers "B.Cu" "B.Mask" "B.Paste")
			(net "P3V3_STBY_CC_R")
			(options
				(clearance outline)
				(anchor circle)
			)
			(primitives
				(gr_poly
					(pts
						(arc
							(start 0.3048 0.2032)
							(mid 0.275042 0.275042)
							(end 0.2032 0.3048)
						)
						(arc
							(start -0.2032 0.3048)
							(mid -0.275042 0.275042)
							(end -0.3048 0.2032)
						)
						(arc
							(start -0.3048 -0.2032)
							(mid -0.275042 -0.275042)
							(end -0.2032 -0.3048)
						)
						(arc
							(start 0.2032 -0.3048)
							(mid 0.275042 -0.275042)
							(end 0.3048 -0.2032)
						)
					)
					(width 0)
					(fill yes)
				)
			)
		)
		(pad "2" smd custom
			(at 0 0.4445 90)
			(size 0.1524 0.1524)
			(layers "B.Cu" "B.Mask" "B.Paste")
			(net "P3V3_STBY_VFB")
			(options
				(clearance outline)
				(anchor circle)
			)
			(primitives
				(gr_poly
					(pts
						(arc
							(start 0.3048 0.2032)
							(mid 0.275042 0.275042)
							(end 0.2032 0.3048)
						)
						(arc
							(start -0.2032 0.3048)
							(mid -0.275042 0.275042)
							(end -0.3048 0.2032)
						)
						(arc
							(start -0.3048 -0.2032)
							(mid -0.275042 -0.275042)
							(end -0.2032 -0.3048)
						)
						(arc
							(start 0.2032 -0.3048)
							(mid 0.275042 -0.275042)
							(end 0.3048 -0.2032)
						)
					)
					(width 0)
					(fill yes)
				)
			)
		)
	)
)
